# T6G (Grand Teton) — schematic netlist excerpt (pin names and nets, part order shuffled) for the footprints in the layout excerpt that follows; sources: Cadence DE-HDL packaged netlist, KiCad conversion of 04192023_DAF0TMB3IC0_F0TG_MB_C_brd_V02_OCP.brd

PR399  Q_RES  49.9 1% CHIP  pkg 0402LF  page 226 : A = GND ; B = PVDD18_SS_P1_RGND
PR393  Q_RES  1 1% CHIP  pkg 0402LF  page 224 : A = PVDD11_S3_P1_VCC ; B = P3V3_AUX
C921  Q_CAP_DIFFBUS  DIFF BUS_0.22UF 6.3V 20% X6S  pkg C0201  page 63 : \1\ = P5E_CPU0_P0_TX_C_DP<6> ; \2\ = P5E_CPU0_P0_TX_DP<6>

(kicad_pcb
	(version 20260206)
	(generator "pcbnew")
	(generator_version "10.0")
	(general
		(thickness 1.6)
		(legacy_teardrops no)
	)
	(paper "A4")
	(title_block
		(title "04192023_DAF0TMB3IC0_F0TG_MB_C_brd_V02_OCP.brd")
		(comment 1 "Grand Teton / footprints 681-683 of 8354")
	)
	(layers
		(0 "F.Cu" signal "TOP")
		(4 "In1.Cu" signal "GND")
		(6 "In2.Cu" signal "IN1")
		(8 "In3.Cu" signal "GND1")
		(10 "In4.Cu" signal "IN2")
		(12 "In5.Cu" signal "GND2")
		(14 "In6.Cu" signal "IN3")
		(16 "In7.Cu" signal "GND3")
		(18 "In8.Cu" signal "VCC")
		(20 "In9.Cu" signal "VCC1")
		(22 "In10.Cu" signal "GND4")
		(24 "In11.Cu" signal "IN4")
		(26 "In12.Cu" signal "GND5")
		(28 "In13.Cu" signal "IN5")
		(30 "In14.Cu" signal "GND6")
		(32 "In15.Cu" signal "IN6")
		(34 "In16.Cu" signal "GND7")
		(2 "B.Cu" signal "BOTTOM")
		(9 "F.Adhes" user "F.Adhesive")
		(11 "B.Adhes" user "B.Adhesive")
		(13 "F.Paste" user "Package Geometry/Pastemask Top")
		(15 "B.Paste" user "Package Geometry/Pastemask Bottom")
		(5 "F.SilkS" user "Ref Des/Silkscreen Top")
		(7 "B.SilkS" user "Ref Des/Silkscreen Bottom")
		(1 "F.Mask" user "Board Geometry/Soldermask Top")
		(3 "B.Mask" user "Board Geometry/Soldermask Bottom")
		(17 "Dwgs.User" user "User.Drawings")
		(19 "Cmts.User" user "User.Comments")
		(21 "Eco1.User" user "User.Eco1")
		(23 "Eco2.User" user "User.Eco2")
		(25 "Edge.Cuts" user "Board Geometry/Outline")
		(27 "Margin" user)
		(31 "F.CrtYd" user "Package Geometry/Place Bound Top")
		(29 "B.CrtYd" user "Package Geometry/Place Bound Bottom")
		(35 "F.Fab" user "Ref Des/Assembly Top")
		(33 "B.Fab" user "Ref Des/Assembly Bottom")
	)
	(footprint ""
		(layer "F.Cu")
		(at 165.576758 -352.27006 90)
		(property "Reference" "PR393"
			(at 0 0 90)
			(layer "F.SilkS")
			(hide yes)
			(effects
				(font
					(size 1.27 1.27)
				)
			)
		)
		(property "Value" ""
			(at 0 0 90)
			(layer "F.Fab")
			(effects
				(font
					(size 1.27 1.27)
				)
			)
		)
		(duplicate_pad_numbers_are_jumpers no)
		(fp_line
			(start 0.7874 -0.4064)
			(end 0.7874 0.4064)
			(stroke
				(width 0.1524)
				(type default)
			)
			(layer "F.SilkS")
		)
		(fp_line
			(start -0.7874 -0.4064)
			(end 0.7874 -0.4064)
			(stroke
				(width 0.1524)
				(type default)
			)
			(layer "F.SilkS")
		)
		(fp_line
			(start 0.7874 0.4064)
			(end -0.7874 0.4064)
			(stroke
				(width 0.1524)
				(type default)
			)
			(layer "F.SilkS")
		)
		(fp_line
			(start -0.7874 0.4064)
			(end -0.7874 -0.4064)
			(stroke
				(width 0.1524)
				(type default)
			)
			(layer "F.SilkS")
		)
		(fp_line
			(start -0.12065 -0.305054)
			(end -0.12065 -0.2794)
			(stroke
				(width 0.1)
				(type default)
			)
			(layer "F.Fab")
		)
		(fp_line
			(start -0.67945 -0.305054)
			(end -0.12065 -0.305054)
			(stroke
				(width 0.1)
				(type default)
			)
			(layer "F.Fab")
		)
		(fp_line
			(start 0.67945 -0.3048)
			(end 0.67945 0.3048)
			(stroke
				(width 0.1)
				(type default)
			)
			(layer "F.Fab")
		)
		(fp_line
			(start 0.12065 -0.3048)
			(end 0.67945 -0.3048)
			(stroke
				(width 0.1)
				(type default)
			)
			(layer "F.Fab")
		)
		(fp_line
			(start 0.12065 -0.2794)
			(end 0.12065 -0.3048)
			(stroke
				(width 0.1)
				(type default)
			)
			(layer "F.Fab")
		)
		(fp_line
			(start -0.12065 -0.2794)
			(end 0.12065 -0.2794)
			(stroke
				(width 0.1)
				(type default)
			)
			(layer "F.Fab")
		)
		(fp_line
			(start 0.120396 0.2794)
			(end -0.12065 0.2794)
			(stroke
				(width 0.1)
				(type default)
			)
			(layer "F.Fab")
		)
		(fp_line
			(start -0.12065 0.2794)
			(end -0.12065 0.3048)
			(stroke
				(width 0.1)
				(type default)
			)
			(layer "F.Fab")
		)
		(fp_line
			(start 0.67945 0.3048)
			(end 0.120396 0.3048)
			(stroke
				(width 0.1)
				(type default)
			)
			(layer "F.Fab")
		)
		(fp_line
			(start 0.120396 0.3048)
			(end 0.120396 0.2794)
			(stroke
				(width 0.1)
				(type default)
			)
			(layer "F.Fab")
		)
		(fp_line
			(start -0.12065 0.3048)
			(end -0.67945 0.3048)
			(stroke
				(width 0.1)
				(type default)
			)
			(layer "F.Fab")
		)
		(fp_line
			(start -0.67945 0.3048)
			(end -0.67945 -0.305054)
			(stroke
				(width 0.1)
				(type default)
			)
			(layer "F.Fab")
		)
		(pad "1" smd circle
			(at -0.40005 0 90)
			(size 0 0)
			(layers "F.Cu" "F.Mask" "F.Paste")
			(net "PVDD11_S3_P1_VCC")
		)
		(pad "2" smd circle
			(at 0.40005 0 90)
			(size 0 0)
			(layers "F.Cu" "F.Mask" "F.Paste")
			(net "P3V3_AUX")
		)
	)
	(footprint ""
		(layer "F.Cu")
		(at 59.135518 -143.656558 -90)
		(property "Reference" "PR399"
			(at 0 0 270)
			(layer "F.SilkS")
			(hide yes)
			(effects
				(font
					(size 1.27 1.27)
				)
			)
		)
		(property "Value" ""
			(at 0 0 270)
			(layer "F.Fab")
			(effects
				(font
					(size 1.27 1.27)
				)
			)
		)
		(duplicate_pad_numbers_are_jumpers no)
		(fp_line
			(start -0.7874 0.4064)
			(end -0.7874 -0.4064)
			(stroke
				(width 0.1524)
				(type default)
			)
			(layer "F.SilkS")
		)
		(fp_line
			(start 0.7874 0.4064)
			(end -0.7874 0.4064)
			(stroke
				(width 0.1524)
				(type default)
			)
			(layer "F.SilkS")
		)
		(fp_line
			(start -0.7874 -0.4064)
			(end 0.7874 -0.4064)
			(stroke
				(width 0.1524)
				(type default)
			)
			(layer "F.SilkS")
		)
		(fp_line
			(start 0.7874 -0.4064)
			(end 0.7874 0.4064)
			(stroke
				(width 0.1524)
				(type default)
			)
			(layer "F.SilkS")
		)
		(fp_line
			(start -0.67945 0.3048)
			(end -0.67945 -0.305054)
			(stroke
				(width 0.1)
				(type default)
			)
			(layer "F.Fab")
		)
		(fp_line
			(start -0.12065 0.3048)
			(end -0.67945 0.3048)
			(stroke
				(width 0.1)
				(type default)
			)
			(layer "F.Fab")
		)
		(fp_line
			(start 0.120396 0.3048)
			(end 0.120396 0.2794)
			(stroke
				(width 0.1)
				(type default)
			)
			(layer "F.Fab")
		)
		(fp_line
			(start 0.67945 0.3048)
			(end 0.120396 0.3048)
			(stroke
				(width 0.1)
				(type default)
			)
			(layer "F.Fab")
		)
		(fp_line
			(start -0.12065 0.2794)
			(end -0.12065 0.3048)
			(stroke
				(width 0.1)
				(type default)
			)
			(layer "F.Fab")
		)
		(fp_line
			(start 0.120396 0.2794)
			(end -0.12065 0.2794)
			(stroke
				(width 0.1)
				(type default)
			)
			(layer "F.Fab")
		)
		(fp_line
			(start -0.12065 -0.2794)
			(end 0.12065 -0.2794)
			(stroke
				(width 0.1)
				(type default)
			)
			(layer "F.Fab")
		)
		(fp_line
			(start 0.12065 -0.2794)
			(end 0.12065 -0.3048)
			(stroke
				(width 0.1)
				(type default)
			)
			(layer "F.Fab")
		)
		(fp_line
			(start 0.12065 -0.3048)
			(end 0.67945 -0.3048)
			(stroke
				(width 0.1)
				(type default)
			)
			(layer "F.Fab")
		)
		(fp_line
			(start 0.67945 -0.3048)
			(end 0.67945 0.3048)
			(stroke
				(width 0.1)
				(type default)
			)
			(layer "F.Fab")
		)
		(fp_line
			(start -0.67945 -0.305054)
			(end -0.12065 -0.305054)
			(stroke
				(width 0.1)
				(type default)
			)
			(layer "F.Fab")
		)
		(fp_line
			(start -0.12065 -0.305054)
			(end -0.12065 -0.2794)
			(stroke
				(width 0.1)
				(type default)
			)
			(layer "F.Fab")
		)
		(pad "1" smd circle
			(at -0.40005 0 270)
			(size 0 0)
			(layers "F.Cu" "F.Mask" "F.Paste")
			(net "GND")
		)
		(pad "2" smd circle
			(at 0.40005 0 270)
			(size 0 0)
			(layers "F.Cu" "F.Mask" "F.Paste")
			(net "PVDD18_SS_P1_RGND")
		)
	)
	(footprint ""
		(layer "F.Cu")
		(at 307.498496 -378.95403 -90)
		(property "Reference" "C921"
			(at 0 0 270)
			(layer "F.SilkS")
			(hide yes)
			(effects
				(font
					(size 1.27 1.27)
				)
			)
		)
		(property "Value" ""
			(at 0 0 270)
			(layer "F.Fab")
			(effects
				(font
					(size 1.27 1.27)
				)
			)
		)
		(duplicate_pad_numbers_are_jumpers no)
		(fp_line
			(start -0.299974 0.150114)
			(end -0.299974 -0.150114)
			(stroke
				(width 0.1)
				(type default)
			)
			(layer "F.Fab")
		)
		(fp_line
			(start 0.299974 0.150114)
			(end -0.299974 0.150114)
			(stroke
				(width 0.1)
				(type default)
			)
			(layer "F.Fab")
		)
		(fp_line
			(start -0.299974 -0.150114)
			(end 0.299974 -0.150114)
			(stroke
				(width 0.1)
				(type default)
			)
			(layer "F.Fab")
		)
		(fp_line
			(start 0.299974 -0.150114)
			(end 0.299974 0.150114)
			(stroke
				(width 0.1)
				(type default)
			)
			(layer "F.Fab")
		)
		(pad "1" smd rect
			(at -0.2667 0 270)
			(size 0.3048 0.381)
			(layers "F.Cu" "F.Mask" "F.Paste")
			(net "P5E_CPU0_P0_TX_C_DP<6>")
		)
		(pad "2" smd rect
			(at 0.2667 0 270)
			(size 0.3048 0.381)
			(layers "F.Cu" "F.Mask" "F.Paste")
			(net "P5E_CPU0_P0_TX_DP<6>")
		)
	)
)
